;LEADER: 12 
;HEADER: 
;CODE  : ASCII 
;FILE  : 9054_F0T_PDB_BD_GPU_F_V04_1213_1550-1-10.drl for  ... layers TOP and BOTTOM
;DESIGN: 9054_F0T_PDB_BD_GPU_F_V04_1213_1550.brd
;   Holesize 1. = 10.000000 Tolerance = +0.000000/-10.000000 PLATED MILS Quantity = 1779
;   Holesize 2. = 22.000000 Tolerance = +3.000000/-3.000000 PLATED MILS Quantity = 32
;   Holesize 3. = 29.520000 Tolerance = +1.960000/-1.960000 PLATED MILS Quantity = 216
;   Holesize 4. = 40.150000 Tolerance = +2.000000/-2.000000 PLATED MILS Quantity = 72
;   Holesize 5. = 41.000000 Tolerance = +3.000000/-3.000000 PLATED MILS Quantity = 32
;   Holesize 6. = 46.000000 Tolerance = +3.000000/-3.000000 PLATED MILS Quantity = 9
;   Holesize 7. = 50.000000 Tolerance = +3.000000/-3.000000 PLATED MILS Quantity = 40
;   Holesize 8. = 67.000000 Tolerance = +3.000000/-3.000000 PLATED MILS Quantity = 12
;   Holesize 9. = 119.000000 Tolerance = +3.000000/-3.000000 PLATED MILS Quantity = 16
;   Holesize 10. = 167.000000 Tolerance = +3.000000/-3.000000 PLATED MILS Quantity = 4
;   Holesize 11. = 203.000000 Tolerance = +2.000000/-2.000000 PLATED MILS Quantity = 2
;   Holesize 12. = 252.000000 Tolerance = +4.000000/-4.000000 PLATED MILS Quantity = 4
;   Holesize 13. = 83.000000 Tolerance = +1.960000/-0.000000 NON_PLATED MILS Quantity = 2
;   Holesize 14. = 85.000000 Tolerance = +2.000000/-2.000000 NON_PLATED MILS Quantity = 4
;   Holesize 15. = 86.000000 Tolerance = +1.180000/-1.180000 NON_PLATED MILS Quantity = 2
;   Holesize 16. = 95.000000 Tolerance = +2.000000/-2.000000 NON_PLATED MILS Quantity = 4
;   Holesize 17. = 125.000000 Tolerance = +2.000000/-0.000000 NON_PLATED MILS Quantity = 3
;   Holesize 18. = 126.000000 Tolerance = +2.000000/-2.000000 NON_PLATED MILS Quantity = 4
;   Holesize 19. = 158.000000 Tolerance = +2.000000/-2.000000 NON_PLATED MILS Quantity = 4
%
G90
X0003018Y0603930
X0015642Y0619715
X0003018Y0503930
X0003018Y0523930
X0003018Y0543930
X0003018Y0563930
X0003018Y0583930
X0003018Y0403930
X0003018Y0423930
X0003018Y0443930
X0003018Y0463930
X0003018Y0483930
X0003018Y0303930
X0003018Y0323930
X0003018Y0343930
X0003018Y0363930
X0003018Y0383930
X0003018Y0203930
X0003018Y0223930
X0003018Y0243930
X0003018Y0263930
X0003018Y0283930
X0003018Y0103930
X0003018Y0123930
X0003018Y0143930
X0003018Y0163930
X0003018Y0183930
X0121406Y0003042
X0101406Y0003042
X0081406Y0003042
X0030709Y0003014
X0010493Y0005830
X0003018Y0023930
X0003018Y0043930
X0003018Y0063930
X0003018Y0083930
X0154778Y0672779
X0174778Y0672779
X0194778Y0672779
X0214778Y0672779
X0035455Y0620194
X0055455Y0620194
X0095455Y0620194
X0075455Y0620194
X0114923Y0623982
X0124901Y0640105
X0210925Y0115575
X0187600Y0106500
X0225829Y0103412
X0200600Y0109059
X0205100Y0123000
X0137355Y0120500
X0134600Y0134000
X0134600Y0150000
X0211425Y0106075
X0176785Y0102000
X0156785Y0101285
X0225891Y0092305
X0225953Y0095780
X0225829Y0099503
X0205061Y0067500
X0205061Y0071500
X0205061Y0075000
X0205061Y0079000
X0205061Y0097000
X0205061Y0093000
X0205061Y0089500
X0205061Y0085500
X0326000Y0074476
X0237391Y0092305
X0233391Y0092305
X0229891Y0092305
X0237453Y0095780
X0233453Y0095780
X0229953Y0095780
X0237329Y0099503
X0233329Y0099503
X0229829Y0099503
X0321000Y0063000
X0324000Y0077000
X0221406Y0003042
X0181406Y0003042
X0201406Y0003042
X0141406Y0003042
X0161406Y0003042
X0320766Y0039211
X0323766Y0039211
X0317766Y0039211
X0314766Y0039211
X0325100Y0064000
X0321500Y0066500
X0317000Y0058000
X0317000Y0064500
X0321500Y0074475
X0317000Y0074475
X0328500Y0015000
X0328500Y0018000
X0328500Y0021000
X0325500Y0021000
X0325500Y0018000
X0325500Y0015000
X0237329Y0103412
X0233329Y0103412
X0229829Y0103412
X0331285Y0620008
X0342119Y0613510
X0234778Y0672779
X0254778Y0672779
X0274778Y0672779
X0294778Y0672779
X0311956Y0651522
X0345412Y0595017
X0345412Y0575017
X0345412Y0555017
X0345412Y0535017
X0345412Y0515017
X0345412Y0495017
X0345412Y0475017
X0345412Y0455017
X0345412Y0435017
X0350024Y0418335
X0362127Y0406608
X0379680Y0402510
X0399680Y0402510
X0419680Y0402510
X0408100Y0224500
X0428277Y0167056
X0408100Y0180100
X0396216Y0046875
X0375192Y0038417
X0378192Y0038417
X0372192Y0038417
X0369192Y0038417
X0330500Y0074476
X0332500Y0063300
X0331500Y0015000
X0331500Y0018000
X0331500Y0021000
X0334500Y0015000
X0334500Y0018000
X0334500Y0021000
X0337500Y0015000
X0337500Y0018000
X0337500Y0021000
X0340500Y0015000
X0340500Y0018000
X0340500Y0021000
X0522084Y0065900
X0522084Y0068900
X0522084Y0071900
X0522084Y0074900
X0522084Y0077900
X0525084Y0065900
X0525084Y0068900
X0525084Y0071900
X0525084Y0074900
X0525084Y0077900
X0528084Y0065900
X0528084Y0068900
X0528084Y0071900
X0528084Y0074900
X0528084Y0077900
X0441938Y0087700
X0489923Y0037456
X0492923Y0037456
X0495923Y0037456
X0498923Y0037456
X0507923Y0037456
X0510923Y0037456
X0504923Y0037456
X0501923Y0037456
X0442738Y0056000
X0445738Y0056000
X0448738Y0056000
X0451738Y0056000
X0454738Y0056000
X0442738Y0068000
X0442738Y0065000
X0442738Y0062000
X0442738Y0059000
X0445738Y0068000
X0445738Y0065000
X0445738Y0062000
X0445738Y0059000
X0448738Y0068000
X0448738Y0065000
X0448738Y0062000
X0448738Y0059000
X0451738Y0068000
X0451738Y0065000
X0451738Y0062000
X0451738Y0059000
X0454738Y0059000
X0454738Y0062000
X0454738Y0065000
X0454738Y0068000
X0442738Y0100400
X0445738Y0100400
X0448738Y0100400
X0451738Y0100400
X0454738Y0100400
X0525084Y0202100
X0525084Y0199100
X0522084Y0202100
X0522084Y0199100
X0522084Y0154700
X0522084Y0160700
X0522084Y0163700
X0522084Y0157700
X0525084Y0154700
X0525084Y0157700
X0525084Y0163700
X0525084Y0160700
X0522084Y0166700
X0525084Y0166700
X0528084Y0110300
X0528084Y0113300
X0528084Y0119300
X0528084Y0116300
X0528084Y0122300
X0522084Y0110300
X0522084Y0116300
X0522084Y0119300
X0522084Y0113300
X0525084Y0110300
X0525084Y0113300
X0525084Y0119300
X0525084Y0116300
X0522084Y0122300
X0525084Y0122300
X0438100Y0170000
X0441938Y0176500
X0441938Y0132100
X0442738Y0112400
X0442738Y0109400
X0442738Y0106400
X0442738Y0103400
X0445738Y0112400
X0445738Y0109400
X0445738Y0106400
X0445738Y0103400
X0448738Y0112400
X0448738Y0109400
X0448738Y0106400
X0448738Y0103400
X0451738Y0112400
X0451738Y0109400
X0451738Y0106400
X0451738Y0103400
X0454738Y0103400
X0454738Y0106400
X0454738Y0109400
X0454738Y0112400
X0442738Y0144800
X0445738Y0144800
X0448738Y0144800
X0451738Y0144800
X0454738Y0144800
X0442738Y0156800
X0442738Y0153800
X0442738Y0150800
X0442738Y0147800
X0445738Y0156800
X0445738Y0153800
X0445738Y0150800
X0445738Y0147800
X0448738Y0156800
X0448738Y0153800
X0448738Y0150800
X0448738Y0147800
X0451738Y0156800
X0451738Y0153800
X0451738Y0150800
X0451738Y0147800
X0454738Y0147800
X0454738Y0150800
X0454738Y0153800
X0454738Y0156800
X0442738Y0189200
X0445738Y0189200
X0448738Y0189200
X0451738Y0189200
X0454738Y0189200
X0442738Y0201200
X0442738Y0198200
X0442738Y0195200
X0442738Y0192200
X0445738Y0201200
X0445738Y0198200
X0445738Y0195200
X0445738Y0192200
X0448738Y0201200
X0448738Y0198200
X0448738Y0195200
X0448738Y0192200
X0451738Y0201200
X0451738Y0198200
X0451738Y0195200
X0451738Y0192200
X0454738Y0192200
X0454738Y0195200
X0454738Y0198200
X0454738Y0201200
X0525084Y0211100
X0522084Y0211100
X0525084Y0205100
X0525084Y0208100
X0522084Y0208100
X0522084Y0205100
X0528084Y0255500
X0528084Y0249500
X0528084Y0252500
X0528084Y0246500
X0528084Y0243500
X0525084Y0255500
X0522084Y0255500
X0525084Y0249500
X0525084Y0252500
X0525084Y0246500
X0525084Y0243500
X0522084Y0246500
X0522084Y0252500
X0522084Y0249500
X0522084Y0243500
X0522084Y0287900
X0522084Y0290900
X0525084Y0290900
X0525084Y0287900
X0528084Y0287900
X0528084Y0290900
X0522084Y0293900
X0525084Y0293900
X0528084Y0293900
X0522084Y0296900
X0525084Y0296900
X0528084Y0296900
X0522084Y0299900
X0525084Y0299900
X0528084Y0299900
X0438100Y0214500
X0430608Y0211389
X0441938Y0265300
X0441938Y0220900
X0442738Y0233600
X0445738Y0233600
X0448738Y0233600
X0451738Y0233600
X0454738Y0233600
X0442738Y0245600
X0442738Y0242600
X0442738Y0239600
X0442738Y0236600
X0445738Y0245600
X0445738Y0242600
X0445738Y0239600
X0445738Y0236600
X0448738Y0245600
X0448738Y0242600
X0448738Y0239600
X0448738Y0236600
X0451738Y0245600
X0451738Y0242600
X0451738Y0239600
X0451738Y0236600
X0454738Y0236600
X0454738Y0239600
X0454738Y0242600
X0454738Y0245600
X0442738Y0278000
X0442738Y0281000
X0442738Y0284000
X0442738Y0287000
X0442738Y0290000
X0445738Y0278000
X0445738Y0281000
X0445738Y0284000
X0445738Y0287000
X0445738Y0290000
X0454738Y0290000
X0454738Y0287000
X0454738Y0284000
X0454738Y0281000
X0451738Y0281000
X0451738Y0284000
X0451738Y0287000
X0451738Y0290000
X0448738Y0281000
X0448738Y0284000
X0448738Y0287000
X0448738Y0290000
X0454738Y0278000
X0451738Y0278000
X0448738Y0278000
X0517410Y0329000
X0506309Y0322000
X0506309Y0329000
X0441938Y0309700
X0517409Y0322000
X0471946Y0357016
X0465946Y0357016
X0468946Y0357016
X0458946Y0357216
X0455946Y0357216
X0455946Y0341216
X0458946Y0341216
X0455946Y0338216
X0458946Y0338216
X0484446Y0341216
X0484446Y0338216
X0478446Y0341216
X0481446Y0341216
X0478446Y0338216
X0481446Y0338216
X0439680Y0402510
X0479680Y0402510
X0459680Y0402510
X0519680Y0402510
X0499680Y0402510
X0465946Y0341216
X0468946Y0341216
X0471946Y0341216
X0465946Y0338216
X0468946Y0338216
X0471946Y0338216
X0618500Y0333500
X0608259Y0305000
X0622184Y0308000
X0616684Y0307975
X0623500Y0379000
X0601675Y0305575
X0559680Y0402510
X0539680Y0402510
X0599680Y0402510
X0579680Y0402510
X0619680Y0402510
X0590684Y0310800
X0590684Y0313800
X0604684Y0267000
X0616184Y0285000
X0604684Y0285000
X0604684Y0276000
X0616184Y0276000
X0616184Y0267000
X0605700Y0259500
X0531084Y0287900
X0531084Y0290900
X0531084Y0293900
X0531084Y0296900
X0531084Y0299900
X0562830Y0266500
X0562830Y0270000
X0570443Y0302702
X0571542Y0289065
X0600875Y0295937
X0562830Y0273500
X0590298Y0276984
X0571325Y0292757
X0565091Y0302592
X0562830Y0277000
X0590298Y0282890
X0609637Y0254523
X0620600Y0239161
X0625684Y0273499
X0629018Y0277500
X0606084Y0293100
X0605800Y0256500
X0620466Y0246839
X0624788Y0235790
X0622288Y0235790
X0580184Y0260000
X0580184Y0257000
X0583184Y0257000
X0583184Y0260000
X0580184Y0254000
X0580184Y0251000
X0580184Y0248000
X0580184Y0245000
X0583184Y0245000
X0583184Y0248000
X0583184Y0251000
X0583184Y0254000
X0580184Y0239000
X0580184Y0242000
X0583184Y0242000
X0583184Y0239000
X0592476Y0239710
X0595276Y0239710
X0602928Y0293969
X0563007Y0247323
X0576467Y0265600
X0616684Y0294500
X0623684Y0281000
X0551430Y0265600
X0563007Y0251677
X0612684Y0297000
X0563007Y0114123
X0574230Y0132400
X0551430Y0132400
X0563007Y0118477
X0562830Y0143800
X0562830Y0140300
X0564305Y0160784
X0562830Y0136800
X0561155Y0160784
X0562830Y0133300
X0580184Y0105800
X0583184Y0105800
X0586184Y0105800
X0580184Y0108800
X0583184Y0108800
X0586184Y0108800
X0580184Y0111800
X0583184Y0111800
X0586184Y0111800
X0580184Y0114800
X0583184Y0114800
X0586184Y0114800
X0580184Y0117800
X0583184Y0117800
X0586184Y0117800
X0580184Y0120800
X0583184Y0120800
X0586184Y0120800
X0580184Y0123800
X0583184Y0123800
X0586184Y0123800
X0586184Y0126800
X0583184Y0126800
X0580184Y0126800
X0531084Y0065900
X0531084Y0068900
X0531084Y0071900
X0531084Y0074900
X0531084Y0077900
X0654784Y0099000
X0657784Y0099000
X0654784Y0096000
X0657784Y0096000
X0651784Y0096000
X0648784Y0096000
X0645784Y0096000
X0651784Y0099000
X0648784Y0099000
X0645784Y0099000
X0654784Y0043500
X0657784Y0043500
X0654784Y0040500
X0657784Y0040500
X0651784Y0040500
X0648784Y0040500
X0645784Y0040500
X0651784Y0043500
X0648784Y0043500
X0645784Y0043500
X0704240Y0185000
X0720100Y0188000
X0723100Y0188000
X0729100Y0188000
X0726100Y0188000
X0723100Y0185000
X0720100Y0185000
X0726100Y0185000
X0729100Y0185000
X0702223Y0197419
X0688900Y0184260
X0693863Y0189760
X0722925Y0299500
X0712000Y0215500
X0698433Y0247119
X0695584Y0268100
X0695684Y0287900
X0686784Y0287900
X0695584Y0278000
X0686784Y0278000
X0686784Y0268100
X0651100Y0266000
X0650100Y0251500
X0706684Y0272400
X0702984Y0272400
X0706684Y0283500
X0702984Y0283500
X0692109Y0248020
X0681684Y0230820
X0691794Y0261073
X0676184Y0274000
X0685884Y0297000
X0679184Y0273190
X0649200Y0254500
X0725000Y0292500
X0719484Y0278980
X0710084Y0261100
X0706984Y0261100
X0717384Y0273400
X0695259Y0248020
X0689684Y0230762
X0688945Y0259761
X0644502Y0246839
X0630308Y0284500
X0639010Y0236377
X0645900Y0242200
X0637684Y0280575
X0704200Y0206569
X0659000Y0284000
X0641000Y0261500
X0729000Y0228500
X0726000Y0228500
X0723000Y0228500
X0720000Y0228500
X0720000Y0231500
X0723000Y0231500
X0729000Y0231500
X0726000Y0231500
X0662184Y0284500
X0662184Y0288500
X0687984Y0212500
X0685484Y0212500
X0681984Y0212500
X0679484Y0212500
X0674984Y0212500
X0672484Y0212500
X0666984Y0212500
X0664484Y0212500
X0727600Y0270000
X0655600Y0237700
X0658600Y0237700
X0662184Y0280500
X0640684Y0269000
X0670184Y0288500
X0640684Y0264500
X0676638Y0230894
X0683592Y0259908
X0654100Y0263000
X0676684Y0280950
X0673684Y0280950
X0660684Y0262500
X0674800Y0269600
X0657259Y0263000
X0679184Y0278980
X0658925Y0320000
X0691759Y0309000
X0662100Y0304500
X0717401Y0329996
X0632186Y0338917
X0657500Y0326925
X0719500Y0315500
X0649059Y0314000
X0663500Y0311500
X0668000Y0311500
X0671000Y0315760
X0639680Y0402510
X0679680Y0402510
X0659680Y0402510
X0719680Y0402510
X0699680Y0402510
X0662125Y0308500
X0675100Y0304500
X0662075Y0320000
X0657500Y0330075
X0693904Y0324032
X0696613Y0324032
X0719433Y0328087
X0710900Y0324100
X0734500Y0310575
X0759680Y0402510
X0739680Y0402510
X0799680Y0402510
X0779680Y0402510
X0819680Y0402510
X0734500Y0307425
X0776000Y0206600
X0770700Y0206900
X0758500Y0228500
X0749500Y0228500
X0752500Y0228500
X0755500Y0228500
X0746500Y0228500
X0732000Y0228500
X0749500Y0231500
X0752500Y0231500
X0755500Y0231500
X0746500Y0231500
X0732000Y0231500
X0758500Y0231500
X0730600Y0270000
X0746600Y0185000
X0749600Y0188000
X0752600Y0188000
X0755600Y0188000
X0758600Y0188000
X0746600Y0188000
X0758600Y0185000
X0755600Y0185000
X0752600Y0185000
X0749600Y0185000
X0732100Y0188000
X0732100Y0185000
X0742554Y0131056
X0742554Y0128056
X0739554Y0128056
X0739554Y0131056
X0736554Y0128056
X0736554Y0131056
X0867100Y0031500
X0867100Y0028000
X0872533Y0029432
X0862600Y0029500
X0885100Y0361500
X0887500Y0355680
X0894500Y0396500
X0880500Y0369500
X0859680Y0402510
X0839680Y0402510
X0899680Y0402510
X0879680Y0402510
X0919680Y0402510
X0878175Y0364709
X0878175Y0374100
X0885265Y0381000
X1026270Y0303729
X1021414Y0355979
X1017300Y0385600
X1017300Y0322500
X0939680Y0402510
X0979680Y0402510
X0959680Y0402510
X1019680Y0402510
X0999680Y0402510
X0978600Y0310955
X1023492Y0346593
X1024525Y0215000
X1027675Y0215000
X0954600Y0207200
X1001000Y0228500
X1010000Y0228500
X1007000Y0228500
X1004000Y0228500
X1013000Y0228500
X0974500Y0228500
X0977500Y0228500
X0980500Y0228500
X0983500Y0228500
X0986500Y0228500
X1013000Y0231500
X0980500Y0231500
X0983500Y0231500
X0986500Y0231500
X0977500Y0231500
X1001000Y0231500
X1010000Y0231500
X1007000Y0231500
X1004000Y0231500
X0974500Y0231500
X1001000Y0185000
X1024600Y0185000
X1007000Y0188000
X1010000Y0188000
X1013000Y0188000
X1013000Y0185000
X1010000Y0185000
X1007000Y0185000
X1004000Y0188000
X1001000Y0188000
X1004000Y0185000
X0974500Y0188000
X0977500Y0188000
X0980500Y0188000
X0977500Y0185000
X0974500Y0185000
X0980500Y0185000
X0983500Y0188000
X0983500Y0185000
X0986500Y0188000
X0986500Y0185000
X0954200Y0200200
X0996954Y0131056
X0996954Y0128056
X0993954Y0128056
X0993954Y0131056
X0990954Y0128056
X0990954Y0131056
X1086500Y0043500
X1083500Y0043500
X1080500Y0043500
X1086500Y0040500
X1083500Y0040500
X1080500Y0040500
X1074500Y0040500
X1077500Y0040500
X1074500Y0043500
X1077500Y0043500
X1086500Y0099000
X1083500Y0099000
X1080500Y0099000
X1086500Y0096000
X1083500Y0096000
X1080500Y0096000
X1074500Y0096000
X1077500Y0096000
X1074500Y0099000
X1077500Y0099000
X1034537Y0201437
X1047163Y0197437
X1070525Y0243000
X1073339Y0292239
X1059300Y0279600
X1055600Y0268500
X1059300Y0268500
X1055600Y0279600
X1074430Y0256461
X1086100Y0278000
X1070490Y0290927
X1083100Y0278810
X1112000Y0296000
X1034360Y0254000
X1042800Y0273020
X1055300Y0290900
X1052200Y0290900
X1044900Y0278600
X1124600Y0271425
X1111100Y0300500
X1121100Y0296000
X1111100Y0285000
X1111100Y0291500
X1102600Y0296000
X1066700Y0283900
X1066600Y0264100
X1075500Y0283900
X1066700Y0274000
X1075500Y0274000
X1075500Y0264100
X1100100Y0247500
X1080600Y0294000
X1101600Y0289500
X1087100Y0282500
X1088079Y0274980
X1105025Y0289000
X1083100Y0273020
X1101500Y0268500
X1118500Y0283000
X1030100Y0207500
X1100500Y0263500
X1100100Y0243500
X1029500Y0281800
X1032500Y0281800
X1070600Y0228000
X1073600Y0228000
X1064600Y0228000
X1061600Y0228000
X1101500Y0271500
X1121600Y0283000
X1121600Y0287500
X1092100Y0263500
X1108100Y0289000
X1085600Y0271050
X1094500Y0360500
X1094500Y0355600
X1123400Y0356300
X1064600Y0324000
X1072600Y0324000
X1067025Y0303980
X1070175Y0303980
X1123100Y0319500
X1123100Y0322500
X1118000Y0303500
X1062600Y0305000
X1080600Y0324000
X1089300Y0339500
X1086800Y0339500
X1079300Y0339500
X1081800Y0339500
X1071300Y0339500
X1073800Y0339500
X1063300Y0339500
X1065800Y0339500
X1122000Y0366240
X1112500Y0364700
X1106000Y0364500
X1059680Y0402510
X1039680Y0402510
X1099680Y0402510
X1079680Y0402510
X1119680Y0402510
X1103661Y0307700
X1106661Y0307700
X1179500Y0355000
X1179500Y0350000
X1153500Y0342500
X1178900Y0359620
X1197127Y0314264
X1201037Y0318912
X1130510Y0307720
X1141600Y0312839
X1130100Y0305174
X1157800Y0312050
X1163000Y0352500
X1166000Y0352500
X1132000Y0367000
X1171700Y0349900
X1178500Y0368740
X1165575Y0340500
X1147000Y0342500
X1225930Y0359148
X1225930Y0356148
X1228930Y0359148
X1228930Y0356148
X1139000Y0366500
X1135000Y0366500
X1143100Y0320000
X1143100Y0322500
X1154600Y0321050
X1141600Y0305161
X1139680Y0402510
X1179680Y0402510
X1159680Y0402510
X1219680Y0402510
X1199680Y0402510
X1168200Y0349700
X1162425Y0340500
X1167800Y0355000
X1176000Y0350000
X1173200Y0316500
X1176200Y0316500
X1138500Y0347500
X1141500Y0347500
X1163266Y0255311
X1199100Y0273500
X1171986Y0269110
X1199100Y0266500
X1199100Y0277000
X1171986Y0275016
X1199100Y0270000
X1201500Y0293284
X1196500Y0293284
X1132113Y0274500
X1136000Y0278953
X1131976Y0267500
X1157138Y0303000
X1154025Y0247000
X1140100Y0244000
X1145600Y0244025
X1156200Y0258900
X1157600Y0285000
X1146100Y0285000
X1146100Y0276000
X1157600Y0276000
X1157600Y0267000
X1146100Y0267000
X1156509Y0295396
X1156584Y0292488
X1160990Y0252134
X1182100Y0239000
X1182100Y0242000
X1182100Y0260000
X1182100Y0257000
X1182100Y0245000
X1182100Y0248000
X1182100Y0251000
X1182100Y0254000
X1179100Y0254000
X1179100Y0251000
X1179100Y0248000
X1179100Y0245000
X1179100Y0257000
X1179100Y0260000
X1179100Y0242000
X1179100Y0239000
X1171600Y0238000
X1171600Y0241500
X1176100Y0239000
X1176100Y0242000
X1176100Y0260000
X1176100Y0257000
X1176100Y0245000
X1176100Y0248000
X1176100Y0251000
X1176100Y0254000
X1187700Y0265600
X1199277Y0251677
X1210500Y0265600
X1199277Y0247323
X1129800Y0265400
X1149600Y0255000
X1143500Y0251500
X1173500Y0298500
X1145600Y0257500
X1197425Y0160284
X1199100Y0136800
X1199100Y0143800
X1199100Y0133300
X1199100Y0140300
X1199277Y0114123
X1210500Y0132400
X1200575Y0160284
X1199277Y0118477
X1187700Y0132400
X1179100Y0126800
X1179100Y0123800
X1179100Y0111800
X1179100Y0114800
X1179100Y0117800
X1179100Y0120800
X1182100Y0120800
X1182100Y0117800
X1182100Y0114800
X1182100Y0111800
X1182100Y0123800
X1182100Y0126800
X1176100Y0120800
X1176100Y0117800
X1176100Y0114800
X1176100Y0111800
X1176100Y0123800
X1176100Y0126800
X1179100Y0105800
X1179100Y0108800
X1182100Y0108800
X1182100Y0105800
X1176100Y0108800
X1176100Y0105800
X1161366Y0038982
X1158366Y0038982
X1152366Y0038982
X1155366Y0038982
X1220866Y0038482
X1223866Y0038482
X1226866Y0038482
X1320346Y0067900
X1231200Y0077900
X1231200Y0074900
X1231200Y0071900
X1231200Y0068900
X1231200Y0065900
X1234200Y0077900
X1234200Y0074900
X1234200Y0071900
X1234200Y0068900
X1234200Y0065900
X1237200Y0077900
X1237200Y0074900
X1237200Y0071900
X1237200Y0068900
X1237200Y0065900
X1240200Y0065900
X1240200Y0068900
X1240200Y0071900
X1240200Y0074900
X1240200Y0077900
X1310366Y0038482
X1307366Y0038482
X1313366Y0038482
X1316366Y0038482
X1270366Y0038482
X1267366Y0038482
X1261366Y0038482
X1264366Y0038482
X1229866Y0038482
X1319700Y0084900
X1319700Y0087900
X1319700Y0090900
X1316700Y0084900
X1316700Y0087900
X1316700Y0090900
X1313700Y0084900
X1313700Y0087900
X1313700Y0090900
X1310700Y0084900
X1310700Y0087900
X1310700Y0090900
X1307700Y0090900
X1307700Y0087900
X1307700Y0084900
X1319700Y0078900
X1319700Y0081900
X1316700Y0078900
X1316700Y0081900
X1313700Y0078900
X1313700Y0081900
X1310700Y0078900
X1310700Y0081900
X1307700Y0081900
X1307700Y0078900
X1240200Y0202100
X1240200Y0199100
X1237200Y0199100
X1237200Y0202100
X1320346Y0156700
X1320346Y0112300
X1240200Y0166700
X1240200Y0163700
X1240200Y0160700
X1240200Y0157700
X1240200Y0154700
X1237200Y0154700
X1237200Y0157700
X1237200Y0160700
X1237200Y0163700
X1237200Y0166700
X1240200Y0122300
X1240200Y0119300
X1240200Y0116300
X1240200Y0113300
X1240200Y0110300
X1237200Y0110300
X1237200Y0113300
X1237200Y0116300
X1237200Y0119300
X1237200Y0122300
X1234200Y0110300
X1234200Y0113300
X1234200Y0116300
X1234200Y0119300
X1234200Y0122300
X1320346Y0201100
X1324100Y0194900
X1324100Y0150500
X1319700Y0129300
X1319700Y0132300
X1319700Y0135300
X1316700Y0129300
X1316700Y0132300
X1316700Y0135300
X1313700Y0129300
X1313700Y0132300
X1313700Y0135300
X1310700Y0129300
X1310700Y0132300
X1310700Y0135300
X1307700Y0135300
X1307700Y0132300
X1307700Y0129300
X1319700Y0123300
X1319700Y0126300
X1316700Y0123300
X1316700Y0126300
X1313700Y0123300
X1313700Y0126300
X1310700Y0123300
X1310700Y0126300
X1307700Y0126300
X1307700Y0123300
X1307700Y0167700
X1307700Y0170700
X1307700Y0173700
X1307700Y0176700
X1307700Y0179700
X1310700Y0179700
X1310700Y0176700
X1310700Y0173700
X1310700Y0170700
X1310700Y0167700
X1313700Y0179700
X1313700Y0176700
X1313700Y0173700
X1313700Y0170700
X1313700Y0167700
X1316700Y0176700
X1316700Y0173700
X1316700Y0170700
X1316700Y0167700
X1319700Y0176700
X1319700Y0173700
X1319700Y0170700
X1319700Y0167700
X1231200Y0299900
X1231200Y0296900
X1231200Y0287900
X1231200Y0290900
X1231200Y0293900
X1240200Y0211100
X1240200Y0205100
X1240200Y0208100
X1237200Y0211100
X1237200Y0208100
X1237200Y0205100
X1240200Y0255500
X1240200Y0249500
X1240200Y0246500
X1240200Y0243500
X1240200Y0252500
X1237200Y0255500
X1234200Y0255500
X1237200Y0252500
X1237200Y0243500
X1237200Y0246500
X1237200Y0249500
X1234200Y0252500
X1234200Y0243500
X1234200Y0246500
X1234200Y0249500
X1234200Y0299900
X1234200Y0293900
X1234200Y0290900
X1234200Y0287900
X1234200Y0296900
X1237200Y0299900
X1237200Y0293900
X1237200Y0290900
X1237200Y0287900
X1237200Y0296900
X1240200Y0296900
X1240200Y0299900
X1240200Y0287900
X1240200Y0290900
X1240200Y0293900
X1320346Y0289900
X1320346Y0245500
X1319700Y0300900
X1316700Y0300900
X1313700Y0300900
X1310700Y0300900
X1307700Y0300900
X1319700Y0262500
X1319700Y0265500
X1319700Y0268500
X1316700Y0262500
X1316700Y0265500
X1316700Y0268500
X1313700Y0262500
X1313700Y0265500
X1313700Y0268500
X1310700Y0262500
X1310700Y0265500
X1310700Y0268500
X1307700Y0268500
X1307700Y0265500
X1307700Y0262500
X1319700Y0256500
X1319700Y0259500
X1316700Y0256500
X1316700Y0259500
X1313700Y0256500
X1313700Y0259500
X1310700Y0256500
X1310700Y0259500
X1307700Y0259500
X1307700Y0256500
X1319700Y0218100
X1319700Y0221100
X1319700Y0224100
X1316700Y0218100
X1316700Y0221100
X1316700Y0224100
X1313700Y0218100
X1313700Y0221100
X1313700Y0224100
X1310700Y0218100
X1310700Y0221100
X1310700Y0224100
X1307700Y0224100
X1307700Y0221100
X1307700Y0218100
X1319700Y0212100
X1319700Y0215100
X1316700Y0212100
X1316700Y0215100
X1313700Y0212100
X1313700Y0215100
X1310700Y0212100
X1310700Y0215100
X1307700Y0215100
X1307700Y0212100
X1255975Y0330000
X1255975Y0337000
X1244874Y0330000
X1271340Y0379784
X1268340Y0379784
X1265340Y0379784
X1247930Y0379648
X1250930Y0379648
X1253930Y0379648
X1231930Y0359148
X1231930Y0356148
X1289113Y0372312
X1292113Y0372312
X1248930Y0356148
X1248930Y0359148
X1245930Y0356148
X1245930Y0359148
X1242930Y0356148
X1242930Y0359148
X1292113Y0375312
X1292113Y0378312
X1289113Y0375312
X1289113Y0378312
X1286113Y0375312
X1286113Y0378312
X1266340Y0356284
X1266340Y0359284
X1263340Y0356284
X1263340Y0359284
X1260340Y0356284
X1260340Y0359284
X1239680Y0402510
X1279680Y0402510
X1259680Y0402510
X1319680Y0402510
X1299680Y0402510
X1316700Y0306900
X1313700Y0306900
X1313700Y0309900
X1310700Y0306900
X1310700Y0309900
X1310700Y0312900
X1307700Y0312900
X1307700Y0309900
X1307700Y0306900
X1319700Y0303900
X1316700Y0303900
X1313700Y0303900
X1310700Y0303900
X1307700Y0303900
X1428754Y0670547
X1420335Y0655388
X1420335Y0635388
X1403035Y0620181
X1389643Y0612723
X1386882Y0594539
X1386882Y0574539
X1386882Y0554539
X1386882Y0534539
X1386882Y0514539
X1386882Y0494539
X1386882Y0474539
X1386882Y0454539
X1386882Y0434539
X1359620Y0402940
X1339680Y0402510
X1355000Y0204400
X1334140Y0146642
X1332671Y0190644
X1355100Y0160000
X1508460Y0003003
X1528460Y0003003
X1425310Y0040481
X1416310Y0040481
X1419310Y0040481
X1422310Y0040481
X1358310Y0038893
X1349310Y0038893
X1352310Y0038893
X1355310Y0038893
X1397230Y0021076
X1397230Y0018076
X1397230Y0015076
X1400230Y0015076
X1400230Y0018076
X1400230Y0021076
X1403230Y0015076
X1403230Y0018076
X1403230Y0021076
X1406230Y0015076
X1406230Y0018076
X1406230Y0021076
X1409230Y0015076
X1409230Y0018076
X1409230Y0021076
X1412230Y0015076
X1412230Y0018076
X1412230Y0021076
X1490228Y0066500
X1494728Y0066500
X1503728Y0074477
X1505100Y0064500
X1527100Y0098925
X1490000Y0084000
X1499228Y0074500
X1490000Y0080500
X1494728Y0083500
X1498180Y0063500
X1524600Y0111500
X1482918Y0107773
X1482918Y0110773
X1482918Y0113773
X1482918Y0104773
X1485918Y0107773
X1485918Y0110773
X1485918Y0113773
X1485918Y0104773
X1488918Y0107773
X1488918Y0110773
X1488918Y0113773
X1488918Y0104773
X1491918Y0104773
X1491918Y0113773
X1491918Y0110773
X1491918Y0107773
X1527100Y0108500
X1628658Y0620261
X1613527Y0627220
X1607226Y0650448
X1602599Y0667628
X1585829Y0672778
X1565829Y0672778
X1545829Y0672778
X1525829Y0672778
X1505829Y0672778
X1485829Y0672778
X1465829Y0672778
X1445829Y0672778
X1629000Y0175000
X1626925Y0156000
X1626000Y0167500
X1626000Y0163500
X1622100Y0155931
X1618100Y0148925
X1624000Y0189000
X1625370Y0103940
X1623100Y0178000
X1623100Y0172500
X1614100Y0130000
X1614100Y0120000
X1614100Y0115000
X1614100Y0110000
X1594930Y0115000
X1622295Y0118940
X1622295Y0114940
X1614100Y0125000
X1624500Y0146000
X1624500Y0142500
X1597100Y0126000
X1597100Y0145000
X1567500Y0067000
X1551000Y0096500
X1531600Y0096941
X1602100Y0062500
X1602100Y0066000
X1602100Y0069500
X1602100Y0082000
X1602100Y0085500
X1602100Y0089000
X1615800Y0076700
X1615800Y0079700
X1615800Y0082700
X1618800Y0082700
X1618800Y0079700
X1618800Y0076700
X1606100Y0062500
X1606100Y0066000
X1606100Y0069500
X1609100Y0062500
X1609100Y0066000
X1609100Y0069500
X1606100Y0082000
X1606100Y0085500
X1606100Y0089000
X1609100Y0082000
X1609100Y0085500
X1609100Y0089000
X1648460Y0003003
X1708460Y0003003
X1695500Y0076500
X1692000Y0076570
X1647800Y0080200
X1647800Y0077200
X1647800Y0083200
X1651037Y0099734
X1647037Y0101434
X1640037Y0101434
X1643537Y0101434
X1657050Y0102380
X1548460Y0003003
X1568460Y0003003
X1588460Y0003003
X1608460Y0003003
X1628460Y0003003
X1721685Y0095940
X1718675Y0093500
X1718675Y0099000
X1718675Y0088000
X1706100Y0092000
X1660000Y0193500
X1654000Y0192500
X1645000Y0184500
X1642000Y0184500
X1658000Y0179500
X1685000Y0133000
X1631323Y0115140
X1707100Y0142500
X1721600Y0198500
X1667600Y0198500
X1705100Y0140500
X1721600Y0194760
X1661500Y0199000
X1701000Y0164500
X1701000Y0159000
X1632336Y0109117
X1641932Y0122969
X1644917Y0124581
X1651325Y0125076
X1656657Y0127365
X1636600Y0173500
X1664000Y0202500
X1645537Y0104134
X1638537Y0104134
X1642037Y0104134
X1675800Y0120400
X1669800Y0120400
X1672800Y0120400
X1646458Y0114450
X1650002Y0114450
X1660250Y0116760
X1657050Y0113860
X1657050Y0116760
X1639372Y0111950
X1642915Y0114450
X1660250Y0113860
X1650002Y0111950
X1646458Y0111950
X1639372Y0114450
X1642915Y0111950
X1709600Y0158000
X1728475Y0175000
X1676350Y0160251
X1688100Y0145560
X1688100Y0162060
X1688100Y0173060
X1657500Y0191500
X1650117Y0180000
X1696600Y0119000
X1701350Y0114250
X1712000Y0153000
X1649500Y0173398
X1667000Y0138000
X1662000Y0106000
X1650990Y0122034
X1649197Y0132915
X1638707Y0132954
X1647837Y0121812
X1629870Y0104240
X1631585Y0188777
X1711025Y0187000
X1729000Y0183500
X1701100Y0178500
X1692600Y0135975
X1685976Y0170000
X1685976Y0175500
X1685976Y0181000
X1679176Y0194760
X1685976Y0148000
X1685976Y0153500
X1685976Y0159000
X1685976Y0164500
X1635000Y0152925
X1702525Y0129500
X1720100Y0179500
X1727200Y0104500
X1685100Y0127500
X1668075Y0189500
X1714175Y0187000
X1704600Y0201500
X1697975Y0181000
X1717600Y0158000
X1720524Y0175000
X1680000Y0156500
X1697976Y0153500
X1697976Y0170000
X1697976Y0175500
X1697976Y0159000
X1697976Y0164500
X1713524Y0119500
X1713525Y0129500
X1713525Y0134500
X1690100Y0127375
X1697976Y0148000
X1713524Y0114500
X1713524Y0109500
X1682500Y0121825
X1658500Y0138000
X1726099Y0153000
X1714100Y0144925
X1721000Y0142525
X1722063Y0156962
X1688100Y0184220
X1672050Y0181550
X1719075Y0112000
X1719075Y0107016
X1701100Y0182000
X1715525Y0153000
X1715525Y0168500
X1727100Y0164280
X1702600Y0171500
X1685975Y0186500
X1721500Y0205000
X1652600Y0212000
X1724824Y0205276
X1702075Y0205500
X1728600Y0387500
X1728600Y0397500
X1815454Y0515746
X1775454Y0515746
X1755454Y0515746
X1729275Y0542751
X1729275Y0562751
X1729275Y0582751
X1729275Y0602751
X1708692Y0620191
X1688692Y0620191
X1668675Y0620226
X1648675Y0620226
X1778838Y0405508
X1784035Y0405535
X1781535Y0405535
X1767600Y0350000
X1767700Y0346200
X1795600Y0308000
X1778838Y0386908
X1778838Y0389508
X1781535Y0386935
X1784035Y0386935
X1781535Y0389535
X1784035Y0389535
X1778838Y0402908
X1784035Y0402935
X1781535Y0402935
X1777383Y0352305
X1769692Y0334649
X1769300Y0329400
X1769300Y0340600
X1747235Y0374964
X1747235Y0371389
X1747235Y0367264
X1747235Y0363689
X1776140Y0364405
X1733600Y0387500
X1731100Y0387500
X1731100Y0397500
X1733600Y0397500
X1776100Y0368500
X1776100Y0371500
X1777383Y0348288
X1767151Y0333311
X1762454Y0320347
X1777532Y0328322
X1777459Y0332322
X1744909Y0334135
X1744909Y0336935
X1744909Y0339735
X1747909Y0334135
X1747909Y0336935
X1747909Y0339735
X1742109Y0334035
X1742109Y0336835
X1742109Y0339635
X1776100Y0361500
X1747235Y0359564
X1747235Y0355989
X1747416Y0351817
X1744909Y0342535
X1744909Y0345335
X1747909Y0342535
X1747909Y0345335
X1751289Y0345227
X1747416Y0348293
X1742109Y0342435
X1742109Y0345235
X1777375Y0356300
X1747925Y0204000
X1740600Y0233000
X1751600Y0233000
X1789600Y0243500
X1740600Y0240500
X1740600Y0238000
X1740600Y0235500
X1751600Y0235500
X1751600Y0238000
X1751600Y0240500
X1766447Y0242798
X1766447Y0239798
X1775447Y0242798
X1775447Y0239798
X1783947Y0242798
X1783947Y0239798
X1766432Y0247301
X1766432Y0250301
X1775432Y0247357
X1775432Y0250357
X1783932Y0247357
X1783932Y0250357
X1751600Y0248000
X1751600Y0250500
X1751600Y0253000
X1740600Y0253000
X1740600Y0250500
X1740600Y0248000
X1789600Y0247000
X1740600Y0255500
X1740600Y0258000
X1751600Y0255500
X1751600Y0258000
X1811500Y0186000
X1778000Y0189500
X1750563Y0198000
X1772975Y0124500
X1809600Y0195000
X1817500Y0188000
X1773500Y0129500
X1764100Y0119500
X1763500Y0113000
X1764000Y0107000
X1773500Y0121000
X1746000Y0191240
X1770075Y0181500
X1768000Y0187260
X1754260Y0187260
X1772500Y0174000
X1769476Y0168500
X1733500Y0173760
X1729411Y0159161
X1738740Y0191500
X1729411Y0143661
X1767075Y0155484
X1763075Y0178900
X1770575Y0137000
X1754925Y0203000
X1769425Y0203000
X1766925Y0181500
X1731925Y0199000
X1763925Y0155484
X1763925Y0170984
X1768500Y0158025
X1759925Y0178900
X1768500Y0142525
X1767425Y0137000
X1773076Y0117500
X1772975Y0104500
X1772975Y0109500
X1773000Y0142525
X1764000Y0142525
X1764000Y0158025
X1738000Y0124500
X1772600Y0177300
X1761600Y0124524
X1767425Y0107000
X1759600Y0114500
X1767525Y0114016
X1800100Y0187500
X1773000Y0158000
X1729255Y0025347
X1729255Y0045347
X1732786Y0058461
X1753635Y0069037
X1773635Y0069037
X1793635Y0069037
X1813635Y0069037
X1833635Y0069037
X1853635Y0069037
X1871009Y0093913
X1871008Y0117112
X1871008Y0137112
X1871008Y0157112
X1871008Y0177112
X1871008Y0197112
X1871008Y0217112
X1871008Y0237112
X1871008Y0257112
X1871008Y0277112
X1871008Y0297112
X1871008Y0317112
X1871008Y0337112
X1871008Y0357112
X1871008Y0377112
X1871008Y0397112
X1847500Y0437000
X1844500Y0416500
X1871008Y0417112
X1871008Y0437112
X1871008Y0457112
X1871008Y0477112
X1871008Y0497112
X1852164Y0419238
X1837164Y0419238
X1837164Y0428238
X1852164Y0435538
X1847164Y0419238
X1842164Y0419238
X1847164Y0430568
X1842164Y0432338
X1855509Y0515697
X1835454Y0515746
M00
X0059055Y0250394
X0049212Y0246457
X0045275Y0236614
X0049212Y0226771
X0059055Y0222834
X0068898Y0226771
X0072835Y0236614
X0068898Y0246457
X0049212Y0401751
X0059055Y0397814
X0068898Y0401751
X0059055Y0425374
X0049212Y0421437
X0045275Y0411594
X0072835Y0411594
X0068898Y0421437
X1673228Y0250394
X1663385Y0246457
X1659448Y0236614
X1663385Y0226771
X1673228Y0222834
X1683071Y0226771
X1687008Y0236614
X1683071Y0246457
X1663385Y0401771
X1673228Y0397834
X1683071Y0401771
X1673228Y0425394
X1663385Y0421457
X1659448Y0411614
X1687008Y0411614
X1683071Y0421457
M00
X0137303Y0664685
X0137303Y0656811
X0137303Y0648937
X0137303Y0641063
X0137303Y0633189
X0137303Y0625315
X0137303Y0617441
X0137303Y0609567
X0145177Y0664685
X0145177Y0656811
X0145177Y0648937
X0145177Y0641063
X0145177Y0633189
X0145177Y0625315
X0145177Y0617441
X0145177Y0609567
X0156004Y0664685
X0156004Y0656811
X0156004Y0648937
X0156004Y0641063
X0156004Y0633189
X0156004Y0625315
X0156004Y0617441
X0156004Y0609567
X0163878Y0664685
X0163878Y0656811
X0163878Y0648937
X0163878Y0641063
X0163878Y0633189
X0163878Y0625315
X0163878Y0617441
X0163878Y0609567
X0223622Y0617441
X0223622Y0625315
X0223622Y0633189
X0215748Y0617441
X0215748Y0625315
X0215748Y0633189
X0200000Y0617441
X0200000Y0625315
X0200000Y0633189
X0192126Y0617441
X0192126Y0625315
X0192126Y0633189
X0200000Y0648937
X0200000Y0656811
X0200000Y0664685
X0192126Y0648937
X0192126Y0656811
X0192126Y0664685
X0223622Y0648937
X0223622Y0656811
X0223622Y0664685
X0215748Y0648937
X0215748Y0656811
X0215748Y0664685
X0137303Y0601693
X0145177Y0601693
X0156004Y0601693
X0163878Y0601693
X0250866Y0010197
X0260866Y0010197
X0250866Y0020827
X0260866Y0020827
X0274646Y0008012
X0284646Y0008012
X0274646Y0018012
X0284646Y0018012
X0279646Y0013012
X0289646Y0013012
X0279646Y0023012
X0289646Y0023012
X0303150Y0617441
X0303150Y0625315
X0303150Y0633189
X0295276Y0633189
X0295276Y0625315
X0295276Y0617441
X0271654Y0625315
X0271654Y0633189
X0279528Y0633189
X0279528Y0625315
X0271654Y0617441
X0279528Y0617441
X0248032Y0625315
X0248032Y0633189
X0255906Y0633189
X0255906Y0625315
X0248032Y0617441
X0255906Y0617441
X0295276Y0656811
X0295276Y0664685
X0303150Y0664685
X0303150Y0656811
X0295276Y0648937
X0303150Y0648937
X0271654Y0656811
X0271654Y0664685
X0279528Y0664685
X0279528Y0656811
X0271654Y0648937
X0279528Y0648937
X0248032Y0656811
X0248032Y0664685
X0255906Y0664685
X0255906Y0656811
X0248032Y0648937
X0255906Y0648937
X1429134Y0625315
X1429134Y0633189
X1429134Y0617441
X1429134Y0656811
X1429134Y0664685
X1429134Y0648937
X1441417Y0010197
X1451417Y0010197
X1441417Y0020827
X1451417Y0020827
X1465197Y0008012
X1475197Y0008012
X1465197Y0018012
X1475197Y0018012
X1470197Y0013012
X1480197Y0013012
X1470197Y0023012
X1480197Y0023012
X1568406Y0664685
X1568406Y0656811
X1568406Y0648937
X1568406Y0641063
X1568406Y0633189
X1568406Y0625315
X1568406Y0617441
X1568406Y0609567
X1576280Y0664685
X1576280Y0656811
X1576280Y0648937
X1576280Y0641063
X1576280Y0633189
X1576280Y0625315
X1576280Y0617441
X1576280Y0609567
X1587107Y0664685
X1587107Y0656811
X1587107Y0648937
X1587107Y0641063
X1587107Y0633189
X1587107Y0625315
X1587107Y0617441
X1587107Y0609567
X1594981Y0664685
X1594981Y0656811
X1594981Y0648937
X1594981Y0641063
X1594981Y0633189
X1594981Y0625315
X1594981Y0617441
X1594981Y0609567
X1540157Y0617441
X1540157Y0625315
X1540157Y0633189
X1532283Y0617441
X1532283Y0625315
X1532283Y0633189
X1540157Y0648937
X1540157Y0656811
X1540157Y0664685
X1532283Y0648937
X1532283Y0656811
X1532283Y0664685
X1568406Y0601693
X1576280Y0601693
X1587107Y0601693
X1594981Y0601693
X1484252Y0617441
X1484252Y0625315
X1484252Y0633189
X1476378Y0633189
X1476378Y0625315
X1476378Y0617441
X1452756Y0625315
X1452756Y0633189
X1460630Y0633189
X1460630Y0625315
X1452756Y0617441
X1460630Y0617441
X1437008Y0633189
X1437008Y0625315
X1437008Y0617441
X1476378Y0656811
X1476378Y0664685
X1484252Y0664685
X1484252Y0656811
X1476378Y0648937
X1484252Y0648937
X1452756Y0656811
X1452756Y0664685
X1460630Y0664685
X1460630Y0656811
X1452756Y0648937
X1460630Y0648937
X1437008Y0664685
X1437008Y0656811
X1437008Y0648937
X1516535Y0617441
X1516535Y0625315
X1516535Y0633189
X1508661Y0617441
X1508661Y0625315
X1508661Y0633189
X1516535Y0648937
X1516535Y0656811
X1516535Y0664685
X1508661Y0648937
X1508661Y0656811
X1508661Y0664685
M00
X0792087Y0220984
X0802087Y0220984
X0812087Y0220984
X0822087Y0220984
X0792087Y0230984
X0802087Y0230984
X0812087Y0230984
X0822087Y0230984
X0792087Y0255984
X0802087Y0255984
X0812087Y0255984
X0822087Y0255984
X0792087Y0265984
X0802087Y0265984
X0812087Y0265984
X0822087Y0265984
X0792087Y0135984
X0802087Y0135984
X0812087Y0135984
X0822087Y0135984
X0792087Y0145984
X0802087Y0145984
X0812087Y0145984
X0822087Y0145984
X0792087Y0170984
X0802087Y0170984
X0812087Y0170984
X0822087Y0170984
X0792087Y0180984
X0802087Y0180984
X0812087Y0180984
X0822087Y0180984
X0792087Y0200984
X0802087Y0200984
X0812087Y0200984
X0822087Y0200984
X0910197Y0135984
X0920197Y0135984
X0910197Y0145984
X0920197Y0145984
X0910197Y0170984
X0920197Y0170984
X0910197Y0180984
X0920197Y0180984
X0910197Y0200984
X0920197Y0200984
X0910197Y0220984
X0920197Y0220984
X0910197Y0230984
X0920197Y0230984
X0910197Y0255984
X0920197Y0255984
X0910197Y0265984
X0920197Y0265984
X0930197Y0220984
X0940197Y0220984
X0930197Y0230984
X0940197Y0230984
X0930197Y0255984
X0940197Y0255984
X0930197Y0265984
X0940197Y0265984
X0930197Y0135984
X0940197Y0135984
X0930197Y0145984
X0940197Y0145984
X0930197Y0170984
X0940197Y0170984
X0930197Y0180984
X0940197Y0180984
X0930197Y0200984
X0940197Y0200984
M00
X1856772Y0230433
X1856772Y0240433
X1856772Y0250433
X1856772Y0260433
X1856772Y0270433
X1856772Y0280433
X1856772Y0290433
X1856772Y0300433
X1846142Y0300433
X1846142Y0290433
X1846142Y0280433
X1846142Y0270433
X1846142Y0260433
X1846142Y0250433
X1846142Y0240433
X1846142Y0230433
X1858957Y0314213
X1858957Y0324213
X1858957Y0334213
X1858957Y0344213
X1853957Y0319213
X1853957Y0329213
X1853957Y0339213
X1853957Y0349213
X1843957Y0319213
X1848957Y0314213
X1843957Y0349213
X1843957Y0339213
X1843957Y0329213
X1848957Y0344213
X1848957Y0334213
X1848957Y0324213
M00
X0825900Y0362200
X0825900Y0372200
X0825900Y0382200
X0866400Y0382200
X0866400Y0372200
X0866400Y0362200
X0906900Y0362200
X0906900Y0372200
X0906900Y0382200
M00
X0166785Y0550000
X0166785Y0520472
X0166785Y0470000
X0166785Y0440472
X0166785Y0390000
X0166785Y0360472
X0166785Y0310000
X0166785Y0280472
X0166785Y0230000
X0166785Y0200472
X0243785Y0200472
X0243785Y0280472
X0243785Y0230000
X0243785Y0390000
X0243785Y0360472
X0243785Y0310000
X0243785Y0470000
X0243785Y0440472
X0243785Y0550000
X0243785Y0520472
X1488500Y0200472
X1488500Y0280472
X1488500Y0230000
X1488500Y0390000
X1488500Y0360472
X1488500Y0310000
X1488500Y0470000
X1488500Y0440472
X1488500Y0550000
X1488500Y0520472
X1565500Y0550000
X1565500Y0520472
X1565500Y0470000
X1565500Y0440472
X1565500Y0390000
X1565500Y0360472
X1565500Y0310000
X1565500Y0280472
X1565500Y0230000
X1565500Y0200472
M00
X0681604Y0593187
X0668420Y0598187
X0681498Y0565042
X0681498Y0575042
X0668314Y0570042
X0681604Y0603187
X0997833Y0603187
X0997833Y0593187
X1011017Y0598187
X0997833Y0565042
X0997833Y0575042
X1011017Y0570042
M00
X0047244Y0017716
X0047244Y0330708
X0279528Y0053148
X0314961Y0561023
X0393702Y0344488
X0748032Y0344488
X0748032Y0064961
X0984252Y0344488
X0984252Y0064961
X1417324Y0561023
X1338584Y0344488
X1452756Y0053149
X1685040Y0017716
X1685040Y0330708
X1799212Y0478346
X1799212Y0096457
M00
X0822087Y0313484
X0822087Y0088484
X0940197Y0313484
X0940197Y0088484
M00
X1848583Y0099212
X1848582Y0481693
M00
X0059055Y0498032
X0032284Y0541339
X1673228Y0498032
X1700000Y0541339
M00
X0207874Y0639095
X1524409Y0639095
M00
X0287402Y0628465
X0263780Y0659961
X1468504Y0628465
X1444882Y0659961
M00
X1851457Y0220433
X1856772Y0360433
M00
X0300866Y0010197
X0240866Y0015512
X1491417Y0010197
X1431417Y0015512
M00
X0231600Y0081000
X1212478Y0300181
X1529100Y0078500
M00
X0822087Y0313484
X0822087Y0088484
X0940197Y0313484
X0940197Y0088484
M00
X0059055Y0236614
X0059055Y0411594
X1673228Y0236614
X1673228Y0411614
M30
